(kicad_pcb
	(version 20260206)
	(generator "pcbnew")
	(generator_version "10.0")
	(general
		(thickness 1.6)
		(legacy_teardrops no)
	)
	(paper "A4")
	(title_block
		(title "Bryce Canyon_R.DPB_16317-1_OCP.brd")
		(comment 1 "Bryce Canyon / footprints 98-103 of 2099")
	)
	(layers
		(0 "F.Cu" signal "TOP")
		(4 "In1.Cu" signal "L2GND")
		(6 "In2.Cu" signal "L3")
		(8 "In3.Cu" signal "L4VCC")
		(10 "In4.Cu" signal "L5VCC")
		(12 "In5.Cu" signal "L6")
		(14 "In6.Cu" signal "L7GND")
		(2 "B.Cu" signal "BOTTOM")
		(9 "F.Adhes" user "F.Adhesive")
		(11 "B.Adhes" user "B.Adhesive")
		(13 "F.Paste" user "Package Geometry/Pastemask Top")
		(15 "B.Paste" user "Package Geometry/Pastemask Bottom")
		(5 "F.SilkS" user "Ref Des/Silkscreen Top")
		(7 "B.SilkS" user "Ref Des/Silkscreen Bottom")
		(1 "F.Mask" user "Board Geometry/Soldermask Top")
		(3 "B.Mask" user "Board Geometry/Soldermask Bottom")
		(17 "Dwgs.User" user "User.Drawings")
		(19 "Cmts.User" user "User.Comments")
		(21 "Eco1.User" user "User.Eco1")
		(23 "Eco2.User" user "User.Eco2")
		(25 "Edge.Cuts" user "Board Geometry/Outline")
		(27 "Margin" user)
		(31 "F.CrtYd" user "Package Geometry/Place Bound Top")
		(29 "B.CrtYd" user "Package Geometry/Place Bound Bottom")
		(35 "F.Fab" user "Ref Des/Assembly Top")
		(33 "B.Fab" user "Ref Des/Assembly Bottom")
	)
	(footprint ""
		(layer "F.Cu")
		(at 433.324 -257.81 -90)
		(property "Reference" "R313"
			(at 0 0 270)
			(layer "F.SilkS")
			(hide yes)
			(effects
				(font
					(size 1.27 1.27)
				)
			)
		)
		(property "Value" "300KR2F-GP"
			(at 0.064008 -3.993896 270)
			(unlocked yes)
			(layer "F.Fab")
			(hide yes)
			(effects
				(font
					(size 1.016 1.016)
					(thickness 0.1524)
				)
			)
		)
		(property "Device Type" "R402H16"
			(at 0.064008 -5.517896 270)
			(unlocked yes)
			(layer "F.Fab")
			(hide yes)
			(effects
				(font
					(size 1.016 1.016)
					(thickness 0.1524)
				)
			)
		)
		(duplicate_pad_numbers_are_jumpers no)
		(fp_line
			(start -0.508 -0.9398)
			(end -0.508 0.9398)
			(stroke
				(width 0.1524)
				(type default)
			)
			(layer "F.SilkS")
		)
		(fp_line
			(start 0.508 -0.9398)
			(end -0.508 -0.9398)
			(stroke
				(width 0.1524)
				(type default)
			)
			(layer "F.SilkS")
		)
		(fp_rect
			(start -0.508 0.9398)
			(end 0.508 -0.9398)
			(stroke
				(width 0)
				(type default)
			)
			(fill no)
			(layer "F.CrtYd")
		)
		(fp_rect
			(start -0.508 0.9398)
			(end 0.508 -0.9398)
			(stroke
				(width 0)
				(type default)
			)
			(fill no)
			(layer "F.Fab")
		)
		(pad "1" smd custom
			(at 0 -0.4445 270)
			(size 0.1397 0.1397)
			(layers "F.Cu" "F.Mask" "F.Paste")
			(net "SW_HDD_N9")
			(options
				(clearance outline)
				(anchor circle)
			)
			(primitives
				(gr_poly
					(pts
						(arc
							(start -0.1778 -0.2794)
							(mid -0.249642 -0.249642)
							(end -0.2794 -0.1778)
						)
						(arc
							(start -0.2794 0.1778)
							(mid -0.249642 0.249642)
							(end -0.1778 0.2794)
						)
						(arc
							(start 0.1778 0.2794)
							(mid 0.249642 0.249642)
							(end 0.2794 0.1778)
						)
						(arc
							(start 0.2794 -0.1778)
							(mid 0.249642 -0.249642)
							(end 0.1778 -0.2794)
						)
					)
					(width 0)
					(fill yes)
				)
			)
		)
		(pad "2" smd custom
			(at 0 0.4445 270)
			(size 0.1397 0.1397)
			(layers "F.Cu" "F.Mask" "F.Paste")
			(net "P12V_B")
			(options
				(clearance outline)
				(anchor circle)
			)
			(primitives
				(gr_poly
					(pts
						(arc
							(start -0.1778 -0.2794)
							(mid -0.249642 -0.249642)
							(end -0.2794 -0.1778)
						)
						(arc
							(start -0.2794 0.1778)
							(mid -0.249642 0.249642)
							(end -0.1778 0.2794)
						)
						(arc
							(start 0.1778 0.2794)
							(mid 0.249642 0.249642)
							(end 0.2794 0.1778)
						)
						(arc
							(start 0.2794 -0.1778)
							(mid 0.249642 -0.249642)
							(end 0.1778 -0.2794)
						)
					)
					(width 0)
					(fill yes)
				)
			)
		)
	)
	(footprint ""
		(layer "F.Cu")
		(at 220.599 -203.5302)
		(property "Reference" "R44"
			(at 0 0 0)
			(layer "F.SilkS")
			(hide yes)
			(effects
				(font
					(size 1.27 1.27)
				)
			)
		)
		(property "Value" "0R2J-2-GP"
			(at 0.064008 -3.993896 0)
			(unlocked yes)
			(layer "F.Fab")
			(hide yes)
			(effects
				(font
					(size 1.016 1.016)
					(thickness 0.1524)
				)
			)
		)
		(property "Device Type" "R402H16"
			(at 0.064008 -5.517896 0)
			(unlocked yes)
			(layer "F.Fab")
			(hide yes)
			(effects
				(font
					(size 1.016 1.016)
					(thickness 0.1524)
				)
			)
		)
		(duplicate_pad_numbers_are_jumpers no)
		(fp_line
			(start -0.508 -0.9398)
			(end -0.508 0.9398)
			(stroke
				(width 0.1524)
				(type default)
			)
			(layer "F.SilkS")
		)
		(fp_line
			(start 0.508 -0.9398)
			(end -0.508 -0.9398)
			(stroke
				(width 0.1524)
				(type default)
			)
			(layer "F.SilkS")
		)
		(fp_rect
			(start -0.508 0.9398)
			(end 0.508 -0.9398)
			(stroke
				(width 0)
				(type default)
			)
			(fill no)
			(layer "F.CrtYd")
		)
		(fp_rect
			(start -0.508 0.9398)
			(end 0.508 -0.9398)
			(stroke
				(width 0)
				(type default)
			)
			(fill no)
			(layer "F.Fab")
		)
		(pad "1" smd custom
			(at 0 -0.4445)
			(size 0.1397 0.1397)
			(layers "F.Cu" "F.Mask" "F.Paste")
			(net "IO_EXP5_INT_N")
			(options
				(clearance outline)
				(anchor circle)
			)
			(primitives
				(gr_poly
					(pts
						(arc
							(start -0.1778 -0.2794)
							(mid -0.249642 -0.249642)
							(end -0.2794 -0.1778)
						)
						(arc
							(start -0.2794 0.1778)
							(mid -0.249642 0.249642)
							(end -0.1778 0.2794)
						)
						(arc
							(start 0.1778 0.2794)
							(mid 0.249642 0.249642)
							(end 0.2794 0.1778)
						)
						(arc
							(start 0.2794 -0.1778)
							(mid 0.249642 -0.249642)
							(end 0.1778 -0.2794)
						)
					)
					(width 0)
					(fill yes)
				)
			)
		)
		(pad "2" smd custom
			(at 0 0.4445)
			(size 0.1397 0.1397)
			(layers "F.Cu" "F.Mask" "F.Paste")
			(net "DRIVE_INSERT_ALERT_B_N")
			(options
				(clearance outline)
				(anchor circle)
			)
			(primitives
				(gr_poly
					(pts
						(arc
							(start -0.1778 -0.2794)
							(mid -0.249642 -0.249642)
							(end -0.2794 -0.1778)
						)
						(arc
							(start -0.2794 0.1778)
							(mid -0.249642 0.249642)
							(end -0.1778 0.2794)
						)
						(arc
							(start 0.1778 0.2794)
							(mid 0.249642 0.249642)
							(end 0.2794 0.1778)
						)
						(arc
							(start 0.2794 -0.1778)
							(mid 0.249642 -0.249642)
							(end 0.1778 -0.2794)
						)
					)
					(width 0)
					(fill yes)
				)
			)
		)
	)
	(footprint ""
		(layer "F.Cu")
		(at 448.002914 -99.706938 180)
		(property "Reference" "Q241"
			(at 0 0 180)
			(layer "F.SilkS")
			(hide yes)
			(effects
				(font
					(size 1.27 1.27)
				)
			)
		)
		(property "Value" "2N7002K-2-GP"
			(at 0.127 -8.9662 180)
			(unlocked yes)
			(layer "F.Fab")
			(hide yes)
			(effects
				(font
					(size 1.016 1.016)
					(thickness 0.1524)
				)
			)
		)
		(property "Device Type" "SOT23DGS2D4H44"
			(at 0.127 -10.4902 180)
			(unlocked yes)
			(layer "F.Fab")
			(hide yes)
			(effects
				(font
					(size 1.016 1.016)
					(thickness 0.1524)
				)
			)
		)
		(duplicate_pad_numbers_are_jumpers no)
		(fp_line
			(start 1.651 1.778)
			(end 1.651 -1.778)
			(stroke
				(width 0.1524)
				(type default)
			)
			(layer "F.SilkS")
		)
		(fp_line
			(start 1.651 -1.778)
			(end -1.651 -1.778)
			(stroke
				(width 0.1524)
				(type default)
			)
			(layer "F.SilkS")
		)
		(fp_line
			(start -1.651 1.778)
			(end 1.651 1.778)
			(stroke
				(width 0.1524)
				(type default)
			)
			(layer "F.SilkS")
		)
		(fp_line
			(start -1.651 -1.778)
			(end -1.651 1.778)
			(stroke
				(width 0.1524)
				(type default)
			)
			(layer "F.SilkS")
		)
		(fp_poly
			(pts
				(xy -1.778 1.8796) (xy -1.778 -1.8796) (xy 1.778 -1.8796) (xy 1.778 1.8796)
			)
			(stroke
				(width 0)
				(type default)
			)
			(fill no)
			(layer "F.CrtYd")
		)
		(fp_poly
			(pts
				(xy -1.778 1.8796) (xy -1.778 -1.8796) (xy 1.778 -1.8796) (xy 1.778 1.8796)
			)
			(stroke
				(width 0)
				(type default)
			)
			(fill no)
			(layer "F.Fab")
		)
		(pad "D" smd custom
			(at 0 -0.9525 180)
			(size 0.1905 0.1905)
			(layers "F.Cu" "F.Mask" "F.Paste")
			(net "FLT_HDD22_N")
			(options
				(clearance outline)
				(anchor circle)
			)
			(primitives
				(gr_poly
					(pts
						(arc
							(start -0.1778 0.5715)
							(mid -0.321484 0.511984)
							(end -0.381 0.3683)
						)
						(arc
							(start -0.381 -0.3683)
							(mid -0.321484 -0.511984)
							(end -0.1778 -0.5715)
						)
						(arc
							(start 0.1778 -0.5715)
							(mid 0.321484 -0.511984)
							(end 0.381 -0.3683)
						)
						(arc
							(start 0.381 0.3683)
							(mid 0.321484 0.511984)
							(end 0.1778 0.5715)
						)
					)
					(width 0)
					(fill yes)
				)
			)
		)
		(pad "G" smd custom
			(at -0.98425 0.9525 180)
			(size 0.1905 0.1905)
			(layers "F.Cu" "F.Mask" "F.Paste")
			(net "DRIVE_B_22_FLT_LED")
			(options
				(clearance outline)
				(anchor circle)
			)
			(primitives
				(gr_poly
					(pts
						(arc
							(start -0.1778 0.5715)
							(mid -0.321484 0.511984)
							(end -0.381 0.3683)
						)
						(arc
							(start -0.381 -0.3683)
							(mid -0.321484 -0.511984)
							(end -0.1778 -0.5715)
						)
						(arc
							(start 0.1778 -0.5715)
							(mid 0.321484 -0.511984)
							(end 0.381 -0.3683)
						)
						(arc
							(start 0.381 0.3683)
							(mid 0.321484 0.511984)
							(end 0.1778 0.5715)
						)
					)
					(width 0)
					(fill yes)
				)
			)
		)
		(pad "S" smd custom
			(at 0.98425 0.9525 180)
			(size 0.1905 0.1905)
			(layers "F.Cu" "F.Mask" "F.Paste")
			(net "GND")
			(options
				(clearance outline)
				(anchor circle)
			)
			(primitives
				(gr_poly
					(pts
						(arc
							(start -0.1778 0.5715)
							(mid -0.321484 0.511984)
							(end -0.381 0.3683)
						)
						(arc
							(start -0.381 -0.3683)
							(mid -0.321484 -0.511984)
							(end -0.1778 -0.5715)
						)
						(arc
							(start 0.1778 -0.5715)
							(mid 0.321484 -0.511984)
							(end 0.381 -0.3683)
						)
						(arc
							(start 0.381 0.3683)
							(mid 0.321484 0.511984)
							(end 0.1778 0.5715)
						)
					)
					(width 0)
					(fill yes)
				)
			)
		)
	)
	(footprint ""
		(layer "F.Cu")
		(at 109.1184 -214.7062 180)
		(property "Reference" "Q222"
			(at 0 0 180)
			(layer "F.SilkS")
			(hide yes)
			(effects
				(font
					(size 1.27 1.27)
				)
			)
		)
		(property "Value" "2N7002K-2-GP"
			(at 0.127 -8.9662 180)
			(unlocked yes)
			(layer "F.Fab")
			(hide yes)
			(effects
				(font
					(size 1.016 1.016)
					(thickness 0.1524)
				)
			)
		)
		(property "Device Type" "SOT23DGS2D4H44"
			(at 0.127 -10.4902 180)
			(unlocked yes)
			(layer "F.Fab")
			(hide yes)
			(effects
				(font
					(size 1.016 1.016)
					(thickness 0.1524)
				)
			)
		)
		(duplicate_pad_numbers_are_jumpers no)
		(fp_line
			(start 1.651 1.778)
			(end 1.651 -1.778)
			(stroke
				(width 0.1524)
				(type default)
			)
			(layer "F.SilkS")
		)
		(fp_line
			(start 1.651 -1.778)
			(end -1.651 -1.778)
			(stroke
				(width 0.1524)
				(type default)
			)
			(layer "F.SilkS")
		)
		(fp_line
			(start -1.651 1.778)
			(end 1.651 1.778)
			(stroke
				(width 0.1524)
				(type default)
			)
			(layer "F.SilkS")
		)
		(fp_line
			(start -1.651 -1.778)
			(end -1.651 1.778)
			(stroke
				(width 0.1524)
				(type default)
			)
			(layer "F.SilkS")
		)
		(fp_poly
			(pts
				(xy -1.778 1.8796) (xy -1.778 -1.8796) (xy 1.778 -1.8796) (xy 1.778 1.8796)
			)
			(stroke
				(width 0)
				(type default)
			)
			(fill no)
			(layer "F.CrtYd")
		)
		(fp_poly
			(pts
				(xy -1.778 1.8796) (xy -1.778 -1.8796) (xy 1.778 -1.8796) (xy 1.778 1.8796)
			)
			(stroke
				(width 0)
				(type default)
			)
			(fill no)
			(layer "F.Fab")
		)
		(pad "D" smd custom
			(at 0 -0.9525 180)
			(size 0.1905 0.1905)
			(layers "F.Cu" "F.Mask" "F.Paste")
			(net "FLT_HDD3_N")
			(options
				(clearance outline)
				(anchor circle)
			)
			(primitives
				(gr_poly
					(pts
						(arc
							(start -0.1778 0.5715)
							(mid -0.321484 0.511984)
							(end -0.381 0.3683)
						)
						(arc
							(start -0.381 -0.3683)
							(mid -0.321484 -0.511984)
							(end -0.1778 -0.5715)
						)
						(arc
							(start 0.1778 -0.5715)
							(mid 0.321484 -0.511984)
							(end 0.381 -0.3683)
						)
						(arc
							(start 0.381 0.3683)
							(mid 0.321484 0.511984)
							(end 0.1778 0.5715)
						)
					)
					(width 0)
					(fill yes)
				)
			)
		)
		(pad "G" smd custom
			(at -0.98425 0.9525 180)
			(size 0.1905 0.1905)
			(layers "F.Cu" "F.Mask" "F.Paste")
			(net "DRIVE_B_3_FLT_LED")
			(options
				(clearance outline)
				(anchor circle)
			)
			(primitives
				(gr_poly
					(pts
						(arc
							(start -0.1778 0.5715)
							(mid -0.321484 0.511984)
							(end -0.381 0.3683)
						)
						(arc
							(start -0.381 -0.3683)
							(mid -0.321484 -0.511984)
							(end -0.1778 -0.5715)
						)
						(arc
							(start 0.1778 -0.5715)
							(mid 0.321484 -0.511984)
							(end 0.381 -0.3683)
						)
						(arc
							(start 0.381 0.3683)
							(mid 0.321484 0.511984)
							(end 0.1778 0.5715)
						)
					)
					(width 0)
					(fill yes)
				)
			)
		)
		(pad "S" smd custom
			(at 0.98425 0.9525 180)
			(size 0.1905 0.1905)
			(layers "F.Cu" "F.Mask" "F.Paste")
			(net "GND")
			(options
				(clearance outline)
				(anchor circle)
			)
			(primitives
				(gr_poly
					(pts
						(arc
							(start -0.1778 0.5715)
							(mid -0.321484 0.511984)
							(end -0.381 0.3683)
						)
						(arc
							(start -0.381 -0.3683)
							(mid -0.321484 -0.511984)
							(end -0.1778 -0.5715)
						)
						(arc
							(start 0.1778 -0.5715)
							(mid 0.321484 -0.511984)
							(end 0.381 -0.3683)
						)
						(arc
							(start 0.381 0.3683)
							(mid 0.321484 0.511984)
							(end 0.1778 0.5715)
						)
					)
					(width 0)
					(fill yes)
				)
			)
		)
	)
	(footprint ""
		(layer "F.Cu")
		(at 57.371996 -360.934 90)
		(property "Reference" "C520"
			(at 0 0 90)
			(layer "F.SilkS")
			(hide yes)
			(effects
				(font
					(size 1.27 1.27)
				)
			)
		)
		(property "Value" "SC22U25V0MX-2-GP"
			(at -0.00254 -4.78536 90)
			(unlocked yes)
			(layer "F.Fab")
			(hide yes)
			(effects
				(font
					(size 1.016 1.016)
					(thickness 0.1524)
				)
			)
		)
		(property "Device Type" "C1210H111"
			(at -0.00254 -6.38048 90)
			(unlocked yes)
			(layer "F.Fab")
			(hide yes)
			(effects
				(font
					(size 1.016 1.016)
					(thickness 0.1524)
				)
			)
		)
		(duplicate_pad_numbers_are_jumpers no)
		(fp_line
			(start 1.5748 -2.3368)
			(end -1.5748 -2.3368)
			(stroke
				(width 0.1524)
				(type default)
			)
			(layer "F.SilkS")
		)
		(fp_line
			(start -1.5748 -2.3368)
			(end -1.5748 -0.762)
			(stroke
				(width 0.1524)
				(type default)
			)
			(layer "F.SilkS")
		)
		(fp_line
			(start 1.5748 -0.762)
			(end 1.5748 -2.3368)
			(stroke
				(width 0.1524)
				(type default)
			)
			(layer "F.SilkS")
		)
		(fp_line
			(start -1.5748 0.762)
			(end -1.5748 2.3368)
			(stroke
				(width 0.1524)
				(type default)
			)
			(layer "F.SilkS")
		)
		(fp_line
			(start 1.5748 2.3368)
			(end 1.5748 0.762)
			(stroke
				(width 0.1524)
				(type default)
			)
			(layer "F.SilkS")
		)
		(fp_line
			(start -1.5748 2.3368)
			(end 1.5748 2.3368)
			(stroke
				(width 0.1524)
				(type default)
			)
			(layer "F.SilkS")
		)
		(fp_rect
			(start -1.651 2.413)
			(end 1.651 -2.413)
			(stroke
				(width 0)
				(type default)
			)
			(fill no)
			(layer "F.CrtYd")
		)
		(fp_poly
			(pts
				(xy 1.651 2.413) (xy 1.651 -2.413) (xy -1.651 -2.413) (xy -1.651 2.413)
			)
			(stroke
				(width 0)
				(type default)
			)
			(fill no)
			(layer "F.Fab")
		)
		(pad "1" smd rect
			(at 0 -1.4732 90)
			(size 2.794 1.397)
			(layers "F.Cu" "F.Mask" "F.Paste")
			(net "P12V_FAN0")
		)
		(pad "2" smd rect
			(at 0 1.4732 90)
			(size 2.794 1.397)
			(layers "F.Cu" "F.Mask" "F.Paste")
			(net "GND")
		)
	)
	(footprint ""
		(layer "F.Cu")
		(at 170.688 -361.696)
		(property "Reference" "R1004"
			(at 0 0 0)
			(layer "F.SilkS")
			(hide yes)
			(effects
				(font
					(size 1.27 1.27)
				)
			)
		)
		(property "Value" "10KR2J-L-GP"
			(at 0.064008 -3.993896 0)
			(unlocked yes)
			(layer "F.Fab")
			(hide yes)
			(effects
				(font
					(size 1.016 1.016)
					(thickness 0.1524)
				)
			)
		)
		(property "Device Type" "R402H15"
			(at 0.064008 -5.517896 0)
			(unlocked yes)
			(layer "F.Fab")
			(hide yes)
			(effects
				(font
					(size 1.016 1.016)
					(thickness 0.1524)
				)
			)
		)
		(duplicate_pad_numbers_are_jumpers no)
		(fp_line
			(start -0.508 -0.9398)
			(end -0.508 0.9398)
			(stroke
				(width 0.1524)
				(type default)
			)
			(layer "F.SilkS")
		)
		(fp_line
			(start 0.508 -0.9398)
			(end -0.508 -0.9398)
			(stroke
				(width 0.1524)
				(type default)
			)
			(layer "F.SilkS")
		)
		(fp_rect
			(start -0.508 0.9398)
			(end 0.508 -0.9398)
			(stroke
				(width 0)
				(type default)
			)
			(fill no)
			(layer "F.CrtYd")
		)
		(fp_rect
			(start -0.508 0.9398)
			(end 0.508 -0.9398)
			(stroke
				(width 0)
				(type default)
			)
			(fill no)
			(layer "F.Fab")
		)
		(pad "1" smd custom
			(at 0 -0.4445)
			(size 0.1397 0.1397)
			(layers "F.Cu" "F.Mask" "F.Paste")
			(net "MB0_PSET_R")
			(options
				(clearance outline)
				(anchor circle)
			)
			(primitives
				(gr_poly
					(pts
						(arc
							(start -0.1778 -0.2794)
							(mid -0.249642 -0.249642)
							(end -0.2794 -0.1778)
						)
						(arc
							(start -0.2794 0.1778)
							(mid -0.249642 0.249642)
							(end -0.1778 0.2794)
						)
						(arc
							(start 0.1778 0.2794)
							(mid 0.249642 0.249642)
							(end 0.2794 0.1778)
						)
						(arc
							(start 0.2794 -0.1778)
							(mid 0.249642 -0.249642)
							(end 0.1778 -0.2794)
						)
					)
					(width 0)
					(fill yes)
				)
			)
		)
		(pad "2" smd custom
			(at 0 0.4445)
			(size 0.1397 0.1397)
			(layers "F.Cu" "F.Mask" "F.Paste")
			(net "AGND_CURRENT_MON")
			(options
				(clearance outline)
				(anchor circle)
			)
			(primitives
				(gr_poly
					(pts
						(arc
							(start -0.1778 -0.2794)
							(mid -0.249642 -0.249642)
							(end -0.2794 -0.1778)
						)
						(arc
							(start -0.2794 0.1778)
							(mid -0.249642 0.249642)
							(end -0.1778 0.2794)
						)
						(arc
							(start 0.1778 0.2794)
							(mid 0.249642 0.249642)
							(end 0.2794 0.1778)
						)
						(arc
							(start 0.2794 -0.1778)
							(mid 0.249642 -0.249642)
							(end 0.1778 -0.2794)
						)
					)
					(width 0)
					(fill yes)
				)
			)
		)
	)
)
